(kicad_pcb
	(version 20260206)
	(generator "pcbnew")
	(generator_version "10.0")
	(general
		(thickness 1.6)
		(legacy_teardrops no)
	)
	(paper "A4")
	(title_block
		(title "01162023_DA0F0TEBIF0_F0T_Expander_BD_F_brd_V02_OCP.brd")
		(comment 1 "Grand Teton / footprints 1321-1328 of 9728")
	)
	(layers
		(0 "F.Cu" signal "TOP")
		(4 "In1.Cu" signal "GND")
		(6 "In2.Cu" signal "VCC")
		(8 "In3.Cu" signal "VCC1")
		(10 "In4.Cu" signal "GND1")
		(12 "In5.Cu" signal "IN1")
		(14 "In6.Cu" signal "GND2")
		(16 "In7.Cu" signal "IN2")
		(18 "In8.Cu" signal "GND3")
		(20 "In9.Cu" signal "IN3")
		(22 "In10.Cu" signal "GND4")
		(24 "In11.Cu" signal "IN4")
		(26 "In12.Cu" signal "GND5")
		(28 "In13.Cu" signal "IN5")
		(30 "In14.Cu" signal "GND6")
		(32 "In15.Cu" signal "IN6")
		(34 "In16.Cu" signal "GND7")
		(2 "B.Cu" signal "BOTTOM")
		(9 "F.Adhes" user "F.Adhesive")
		(11 "B.Adhes" user "B.Adhesive")
		(13 "F.Paste" user "Package Geometry/Pastemask Top")
		(15 "B.Paste" user "Package Geometry/Pastemask Bottom")
		(5 "F.SilkS" user "Ref Des/Silkscreen Top")
		(7 "B.SilkS" user "Ref Des/Silkscreen Bottom")
		(1 "F.Mask" user "Board Geometry/Soldermask Top")
		(3 "B.Mask" user "Board Geometry/Soldermask Bottom")
		(17 "Dwgs.User" user "User.Drawings")
		(19 "Cmts.User" user "User.Comments")
		(21 "Eco1.User" user "User.Eco1")
		(23 "Eco2.User" user "User.Eco2")
		(25 "Edge.Cuts" user "Board Geometry/Outline")
		(27 "Margin" user)
		(31 "F.CrtYd" user "Package Geometry/Place Bound Top")
		(29 "B.CrtYd" user "Package Geometry/Place Bound Bottom")
		(35 "F.Fab" user "Ref Des/Assembly Top")
		(33 "B.Fab" user "Ref Des/Assembly Bottom")
	)
	(footprint ""
		(layer "F.Cu")
		(at 456.396852 -280.224484 180)
		(property "Reference" "C631"
			(at 0 0 180)
			(layer "F.SilkS")
			(hide yes)
			(effects
				(font
					(size 1.27 1.27)
				)
			)
		)
		(property "Value" ""
			(at 0 0 180)
			(layer "F.Fab")
			(effects
				(font
					(size 1.27 1.27)
				)
			)
		)
		(duplicate_pad_numbers_are_jumpers no)
		(fp_line
			(start 0.7874 0.4064)
			(end -0.7874 0.4064)
			(stroke
				(width 0.1524)
				(type default)
			)
			(layer "F.SilkS")
		)
		(fp_line
			(start 0.7874 -0.4064)
			(end 0.7874 0.4064)
			(stroke
				(width 0.1524)
				(type default)
			)
			(layer "F.SilkS")
		)
		(fp_line
			(start -0.7874 0.4064)
			(end -0.7874 -0.4064)
			(stroke
				(width 0.1524)
				(type default)
			)
			(layer "F.SilkS")
		)
		(fp_line
			(start -0.7874 -0.4064)
			(end 0.7874 -0.4064)
			(stroke
				(width 0.1524)
				(type default)
			)
			(layer "F.SilkS")
		)
		(fp_line
			(start 0.67945 0.3048)
			(end 0.120396 0.3048)
			(stroke
				(width 0.1)
				(type default)
			)
			(layer "F.Fab")
		)
		(fp_line
			(start 0.67945 -0.3048)
			(end 0.67945 0.3048)
			(stroke
				(width 0.1)
				(type default)
			)
			(layer "F.Fab")
		)
		(fp_line
			(start 0.12065 -0.2794)
			(end 0.12065 -0.3048)
			(stroke
				(width 0.1)
				(type default)
			)
			(layer "F.Fab")
		)
		(fp_line
			(start 0.12065 -0.3048)
			(end 0.67945 -0.3048)
			(stroke
				(width 0.1)
				(type default)
			)
			(layer "F.Fab")
		)
		(fp_line
			(start 0.120396 0.3048)
			(end 0.120396 0.2794)
			(stroke
				(width 0.1)
				(type default)
			)
			(layer "F.Fab")
		)
		(fp_line
			(start 0.120396 0.2794)
			(end -0.12065 0.2794)
			(stroke
				(width 0.1)
				(type default)
			)
			(layer "F.Fab")
		)
		(fp_line
			(start -0.12065 0.3048)
			(end -0.67945 0.3048)
			(stroke
				(width 0.1)
				(type default)
			)
			(layer "F.Fab")
		)
		(fp_line
			(start -0.12065 0.2794)
			(end -0.12065 0.3048)
			(stroke
				(width 0.1)
				(type default)
			)
			(layer "F.Fab")
		)
		(fp_line
			(start -0.12065 -0.2794)
			(end 0.12065 -0.2794)
			(stroke
				(width 0.1)
				(type default)
			)
			(layer "F.Fab")
		)
		(fp_line
			(start -0.12065 -0.305054)
			(end -0.12065 -0.2794)
			(stroke
				(width 0.1)
				(type default)
			)
			(layer "F.Fab")
		)
		(fp_line
			(start -0.67945 0.3048)
			(end -0.67945 -0.305054)
			(stroke
				(width 0.1)
				(type default)
			)
			(layer "F.Fab")
		)
		(fp_line
			(start -0.67945 -0.305054)
			(end -0.12065 -0.305054)
			(stroke
				(width 0.1)
				(type default)
			)
			(layer "F.Fab")
		)
		(pad "1" smd circle
			(at -0.40005 0 180)
			(size 0 0)
			(layers "F.Cu" "F.Mask" "F.Paste")
			(net "P3V3_AUX")
		)
		(pad "2" smd circle
			(at 0.40005 0 180)
			(size 0 0)
			(layers "F.Cu" "F.Mask" "F.Paste")
			(net "GND")
		)
	)
	(footprint ""
		(layer "F.Cu")
		(at 175.0949 -99.750372 180)
		(property "Reference" "R181"
			(at 0 0 180)
			(layer "F.SilkS")
			(hide yes)
			(effects
				(font
					(size 1.27 1.27)
				)
			)
		)
		(property "Value" ""
			(at 0 0 180)
			(layer "F.Fab")
			(effects
				(font
					(size 1.27 1.27)
				)
			)
		)
		(duplicate_pad_numbers_are_jumpers no)
		(fp_line
			(start 0.7874 0.4064)
			(end -0.7874 0.4064)
			(stroke
				(width 0.1524)
				(type default)
			)
			(layer "F.SilkS")
		)
		(fp_line
			(start 0.7874 -0.4064)
			(end 0.7874 0.4064)
			(stroke
				(width 0.1524)
				(type default)
			)
			(layer "F.SilkS")
		)
		(fp_line
			(start -0.7874 0.4064)
			(end -0.7874 -0.4064)
			(stroke
				(width 0.1524)
				(type default)
			)
			(layer "F.SilkS")
		)
		(fp_line
			(start -0.7874 -0.4064)
			(end 0.7874 -0.4064)
			(stroke
				(width 0.1524)
				(type default)
			)
			(layer "F.SilkS")
		)
		(fp_line
			(start 0.67945 0.3048)
			(end 0.120396 0.3048)
			(stroke
				(width 0.1)
				(type default)
			)
			(layer "F.Fab")
		)
		(fp_line
			(start 0.67945 -0.3048)
			(end 0.67945 0.3048)
			(stroke
				(width 0.1)
				(type default)
			)
			(layer "F.Fab")
		)
		(fp_line
			(start 0.12065 -0.2794)
			(end 0.12065 -0.3048)
			(stroke
				(width 0.1)
				(type default)
			)
			(layer "F.Fab")
		)
		(fp_line
			(start 0.12065 -0.3048)
			(end 0.67945 -0.3048)
			(stroke
				(width 0.1)
				(type default)
			)
			(layer "F.Fab")
		)
		(fp_line
			(start 0.120396 0.3048)
			(end 0.120396 0.2794)
			(stroke
				(width 0.1)
				(type default)
			)
			(layer "F.Fab")
		)
		(fp_line
			(start 0.120396 0.2794)
			(end -0.12065 0.2794)
			(stroke
				(width 0.1)
				(type default)
			)
			(layer "F.Fab")
		)
		(fp_line
			(start -0.12065 0.3048)
			(end -0.67945 0.3048)
			(stroke
				(width 0.1)
				(type default)
			)
			(layer "F.Fab")
		)
		(fp_line
			(start -0.12065 0.2794)
			(end -0.12065 0.3048)
			(stroke
				(width 0.1)
				(type default)
			)
			(layer "F.Fab")
		)
		(fp_line
			(start -0.12065 -0.2794)
			(end 0.12065 -0.2794)
			(stroke
				(width 0.1)
				(type default)
			)
			(layer "F.Fab")
		)
		(fp_line
			(start -0.12065 -0.305054)
			(end -0.12065 -0.2794)
			(stroke
				(width 0.1)
				(type default)
			)
			(layer "F.Fab")
		)
		(fp_line
			(start -0.67945 0.3048)
			(end -0.67945 -0.305054)
			(stroke
				(width 0.1)
				(type default)
			)
			(layer "F.Fab")
		)
		(fp_line
			(start -0.67945 -0.305054)
			(end -0.12065 -0.305054)
			(stroke
				(width 0.1)
				(type default)
			)
			(layer "F.Fab")
		)
		(pad "1" smd circle
			(at -0.40005 0 180)
			(size 0 0)
			(layers "F.Cu" "F.Mask" "F.Paste")
			(net "NIC3_SLOT_ID1")
		)
		(pad "2" smd circle
			(at 0.40005 0 180)
			(size 0 0)
			(layers "F.Cu" "F.Mask" "F.Paste")
			(net "GND")
		)
	)
	(footprint ""
		(layer "F.Cu")
		(at 375.18594 -356.244906 90)
		(property "Reference" "C783"
			(at 0 0 90)
			(layer "F.SilkS")
			(hide yes)
			(effects
				(font
					(size 1.27 1.27)
				)
			)
		)
		(property "Value" ""
			(at 0 0 90)
			(layer "F.Fab")
			(effects
				(font
					(size 1.27 1.27)
				)
			)
		)
		(duplicate_pad_numbers_are_jumpers no)
		(fp_line
			(start 0.299974 -0.150114)
			(end 0.299974 0.150114)
			(stroke
				(width 0.1)
				(type default)
			)
			(layer "F.Fab")
		)
		(fp_line
			(start -0.299974 -0.150114)
			(end 0.299974 -0.150114)
			(stroke
				(width 0.1)
				(type default)
			)
			(layer "F.Fab")
		)
		(fp_line
			(start 0.299974 0.150114)
			(end -0.299974 0.150114)
			(stroke
				(width 0.1)
				(type default)
			)
			(layer "F.Fab")
		)
		(fp_line
			(start -0.299974 0.150114)
			(end -0.299974 -0.150114)
			(stroke
				(width 0.1)
				(type default)
			)
			(layer "F.Fab")
		)
		(pad "1" smd rect
			(at -0.2667 0 90)
			(size 0.3048 0.381)
			(layers "F.Cu" "F.Mask" "F.Paste")
			(net "P5E_PEX3_STN6_TX_DN<101>")
		)
		(pad "2" smd rect
			(at 0.2667 0 90)
			(size 0.3048 0.381)
			(layers "F.Cu" "F.Mask" "F.Paste")
			(net "P5E_PEX3_STN6_TX_C_DN<101>")
		)
	)
	(footprint ""
		(layer "F.Cu")
		(at 428.319438 -130.794506 180)
		(property "Reference" "C656"
			(at 0 0 180)
			(layer "F.SilkS")
			(hide yes)
			(effects
				(font
					(size 1.27 1.27)
				)
			)
		)
		(property "Value" ""
			(at 0 0 180)
			(layer "F.Fab")
			(effects
				(font
					(size 1.27 1.27)
				)
			)
		)
		(duplicate_pad_numbers_are_jumpers no)
		(fp_line
			(start 0.299974 0.150114)
			(end -0.299974 0.150114)
			(stroke
				(width 0.1)
				(type default)
			)
			(layer "F.Fab")
		)
		(fp_line
			(start 0.299974 -0.150114)
			(end 0.299974 0.150114)
			(stroke
				(width 0.1)
				(type default)
			)
			(layer "F.Fab")
		)
		(fp_line
			(start -0.299974 0.150114)
			(end -0.299974 -0.150114)
			(stroke
				(width 0.1)
				(type default)
			)
			(layer "F.Fab")
		)
		(fp_line
			(start -0.299974 -0.150114)
			(end 0.299974 -0.150114)
			(stroke
				(width 0.1)
				(type default)
			)
			(layer "F.Fab")
		)
		(pad "1" smd rect
			(at -0.2667 0 180)
			(size 0.3048 0.381)
			(layers "F.Cu" "F.Mask" "F.Paste")
			(net "P5E_PEX3_STN0_TX_DP<4>")
		)
		(pad "2" smd rect
			(at 0.2667 0 180)
			(size 0.3048 0.381)
			(layers "F.Cu" "F.Mask" "F.Paste")
			(net "P5E_PEX3_STN0_TX_C_DP<4>")
		)
	)
	(footprint ""
		(layer "F.Cu")
		(at 388.898384 -250.070874 -90)
		(property "Reference" "R1406"
			(at 0 0 270)
			(layer "F.SilkS")
			(hide yes)
			(effects
				(font
					(size 1.27 1.27)
				)
			)
		)
		(property "Value" ""
			(at 0 0 270)
			(layer "F.Fab")
			(effects
				(font
					(size 1.27 1.27)
				)
			)
		)
		(duplicate_pad_numbers_are_jumpers no)
		(fp_line
			(start -0.7874 0.4064)
			(end -0.7874 -0.4064)
			(stroke
				(width 0.1524)
				(type default)
			)
			(layer "F.SilkS")
		)
		(fp_line
			(start 0.7874 0.4064)
			(end -0.7874 0.4064)
			(stroke
				(width 0.1524)
				(type default)
			)
			(layer "F.SilkS")
		)
		(fp_line
			(start -0.7874 -0.4064)
			(end 0.7874 -0.4064)
			(stroke
				(width 0.1524)
				(type default)
			)
			(layer "F.SilkS")
		)
		(fp_line
			(start 0.7874 -0.4064)
			(end 0.7874 0.4064)
			(stroke
				(width 0.1524)
				(type default)
			)
			(layer "F.SilkS")
		)
		(fp_line
			(start -0.67945 0.3048)
			(end -0.67945 -0.305054)
			(stroke
				(width 0.1)
				(type default)
			)
			(layer "F.Fab")
		)
		(fp_line
			(start -0.12065 0.3048)
			(end -0.67945 0.3048)
			(stroke
				(width 0.1)
				(type default)
			)
			(layer "F.Fab")
		)
		(fp_line
			(start 0.120396 0.3048)
			(end 0.120396 0.2794)
			(stroke
				(width 0.1)
				(type default)
			)
			(layer "F.Fab")
		)
		(fp_line
			(start 0.67945 0.3048)
			(end 0.120396 0.3048)
			(stroke
				(width 0.1)
				(type default)
			)
			(layer "F.Fab")
		)
		(fp_line
			(start -0.12065 0.2794)
			(end -0.12065 0.3048)
			(stroke
				(width 0.1)
				(type default)
			)
			(layer "F.Fab")
		)
		(fp_line
			(start 0.120396 0.2794)
			(end -0.12065 0.2794)
			(stroke
				(width 0.1)
				(type default)
			)
			(layer "F.Fab")
		)
		(fp_line
			(start -0.12065 -0.2794)
			(end 0.12065 -0.2794)
			(stroke
				(width 0.1)
				(type default)
			)
			(layer "F.Fab")
		)
		(fp_line
			(start 0.12065 -0.2794)
			(end 0.12065 -0.3048)
			(stroke
				(width 0.1)
				(type default)
			)
			(layer "F.Fab")
		)
		(fp_line
			(start 0.12065 -0.3048)
			(end 0.67945 -0.3048)
			(stroke
				(width 0.1)
				(type default)
			)
			(layer "F.Fab")
		)
		(fp_line
			(start 0.67945 -0.3048)
			(end 0.67945 0.3048)
			(stroke
				(width 0.1)
				(type default)
			)
			(layer "F.Fab")
		)
		(fp_line
			(start -0.67945 -0.305054)
			(end -0.12065 -0.305054)
			(stroke
				(width 0.1)
				(type default)
			)
			(layer "F.Fab")
		)
		(fp_line
			(start -0.12065 -0.305054)
			(end -0.12065 -0.2794)
			(stroke
				(width 0.1)
				(type default)
			)
			(layer "F.Fab")
		)
		(pad "1" smd circle
			(at -0.40005 0 270)
			(size 0 0)
			(layers "F.Cu" "F.Mask" "F.Paste")
			(net "PEX3_MODE_SEL1")
		)
		(pad "2" smd circle
			(at 0.40005 0 270)
			(size 0 0)
			(layers "F.Cu" "F.Mask" "F.Paste")
			(net "P1V8_PEX")
		)
	)
	(footprint ""
		(layer "F.Cu")
		(at 98.674936 -56.977534 180)
		(property "Reference" "PC354"
			(at 0 0 180)
			(layer "F.SilkS")
			(hide yes)
			(effects
				(font
					(size 1.27 1.27)
				)
			)
		)
		(property "Value" ""
			(at 0 0 180)
			(layer "F.Fab")
			(effects
				(font
					(size 1.27 1.27)
				)
			)
		)
		(duplicate_pad_numbers_are_jumpers no)
		(fp_line
			(start 0.7874 0.4064)
			(end -0.7874 0.4064)
			(stroke
				(width 0.1524)
				(type default)
			)
			(layer "F.SilkS")
		)
		(fp_line
			(start 0.7874 -0.4064)
			(end 0.7874 0.4064)
			(stroke
				(width 0.1524)
				(type default)
			)
			(layer "F.SilkS")
		)
		(fp_line
			(start -0.7874 0.4064)
			(end -0.7874 -0.4064)
			(stroke
				(width 0.1524)
				(type default)
			)
			(layer "F.SilkS")
		)
		(fp_line
			(start -0.7874 -0.4064)
			(end 0.7874 -0.4064)
			(stroke
				(width 0.1524)
				(type default)
			)
			(layer "F.SilkS")
		)
		(fp_line
			(start 0.67945 0.3048)
			(end 0.120396 0.3048)
			(stroke
				(width 0.1)
				(type default)
			)
			(layer "F.Fab")
		)
		(fp_line
			(start 0.67945 -0.3048)
			(end 0.67945 0.3048)
			(stroke
				(width 0.1)
				(type default)
			)
			(layer "F.Fab")
		)
		(fp_line
			(start 0.12065 -0.2794)
			(end 0.12065 -0.3048)
			(stroke
				(width 0.1)
				(type default)
			)
			(layer "F.Fab")
		)
		(fp_line
			(start 0.12065 -0.3048)
			(end 0.67945 -0.3048)
			(stroke
				(width 0.1)
				(type default)
			)
			(layer "F.Fab")
		)
		(fp_line
			(start 0.120396 0.3048)
			(end 0.120396 0.2794)
			(stroke
				(width 0.1)
				(type default)
			)
			(layer "F.Fab")
		)
		(fp_line
			(start 0.120396 0.2794)
			(end -0.12065 0.2794)
			(stroke
				(width 0.1)
				(type default)
			)
			(layer "F.Fab")
		)
		(fp_line
			(start -0.12065 0.3048)
			(end -0.67945 0.3048)
			(stroke
				(width 0.1)
				(type default)
			)
			(layer "F.Fab")
		)
		(fp_line
			(start -0.12065 0.2794)
			(end -0.12065 0.3048)
			(stroke
				(width 0.1)
				(type default)
			)
			(layer "F.Fab")
		)
		(fp_line
			(start -0.12065 -0.2794)
			(end 0.12065 -0.2794)
			(stroke
				(width 0.1)
				(type default)
			)
			(layer "F.Fab")
		)
		(fp_line
			(start -0.12065 -0.305054)
			(end -0.12065 -0.2794)
			(stroke
				(width 0.1)
				(type default)
			)
			(layer "F.Fab")
		)
		(fp_line
			(start -0.67945 0.3048)
			(end -0.67945 -0.305054)
			(stroke
				(width 0.1)
				(type default)
			)
			(layer "F.Fab")
		)
		(fp_line
			(start -0.67945 -0.305054)
			(end -0.12065 -0.305054)
			(stroke
				(width 0.1)
				(type default)
			)
			(layer "F.Fab")
		)
		(pad "1" smd circle
			(at -0.40005 0 180)
			(size 0 0)
			(layers "F.Cu" "F.Mask" "F.Paste")
			(net "P12V_AUX")
		)
		(pad "2" smd circle
			(at 0.40005 0 180)
			(size 0 0)
			(layers "F.Cu" "F.Mask" "F.Paste")
			(net "GND")
		)
	)
	(footprint ""
		(layer "F.Cu")
		(at 143.85163 -260.840982)
		(property "Reference" "R4577"
			(at 0 0 0)
			(layer "F.SilkS")
			(hide yes)
			(effects
				(font
					(size 1.27 1.27)
				)
			)
		)
		(property "Value" ""
			(at 0 0 0)
			(layer "F.Fab")
			(effects
				(font
					(size 1.27 1.27)
				)
			)
		)
		(duplicate_pad_numbers_are_jumpers no)
		(fp_line
			(start -0.7874 -0.4064)
			(end 0.7874 -0.4064)
			(stroke
				(width 0.1524)
				(type default)
			)
			(layer "F.SilkS")
		)
		(fp_line
			(start -0.7874 0.4064)
			(end -0.7874 -0.4064)
			(stroke
				(width 0.1524)
				(type default)
			)
			(layer "F.SilkS")
		)
		(fp_line
			(start 0.7874 -0.4064)
			(end 0.7874 0.4064)
			(stroke
				(width 0.1524)
				(type default)
			)
			(layer "F.SilkS")
		)
		(fp_line
			(start 0.7874 0.4064)
			(end -0.7874 0.4064)
			(stroke
				(width 0.1524)
				(type default)
			)
			(layer "F.SilkS")
		)
		(fp_line
			(start -0.67945 -0.305054)
			(end -0.12065 -0.305054)
			(stroke
				(width 0.1)
				(type default)
			)
			(layer "F.Fab")
		)
		(fp_line
			(start -0.67945 0.3048)
			(end -0.67945 -0.305054)
			(stroke
				(width 0.1)
				(type default)
			)
			(layer "F.Fab")
		)
		(fp_line
			(start -0.12065 -0.305054)
			(end -0.12065 -0.2794)
			(stroke
				(width 0.1)
				(type default)
			)
			(layer "F.Fab")
		)
		(fp_line
			(start -0.12065 -0.2794)
			(end 0.12065 -0.2794)
			(stroke
				(width 0.1)
				(type default)
			)
			(layer "F.Fab")
		)
		(fp_line
			(start -0.12065 0.2794)
			(end -0.12065 0.3048)
			(stroke
				(width 0.1)
				(type default)
			)
			(layer "F.Fab")
		)
		(fp_line
			(start -0.12065 0.3048)
			(end -0.67945 0.3048)
			(stroke
				(width 0.1)
				(type default)
			)
			(layer "F.Fab")
		)
		(fp_line
			(start 0.120396 0.2794)
			(end -0.12065 0.2794)
			(stroke
				(width 0.1)
				(type default)
			)
			(layer "F.Fab")
		)
		(fp_line
			(start 0.120396 0.3048)
			(end 0.120396 0.2794)
			(stroke
				(width 0.1)
				(type default)
			)
			(layer "F.Fab")
		)
		(fp_line
			(start 0.12065 -0.3048)
			(end 0.67945 -0.3048)
			(stroke
				(width 0.1)
				(type default)
			)
			(layer "F.Fab")
		)
		(fp_line
			(start 0.12065 -0.2794)
			(end 0.12065 -0.3048)
			(stroke
				(width 0.1)
				(type default)
			)
			(layer "F.Fab")
		)
		(fp_line
			(start 0.67945 -0.3048)
			(end 0.67945 0.3048)
			(stroke
				(width 0.1)
				(type default)
			)
			(layer "F.Fab")
		)
		(fp_line
			(start 0.67945 0.3048)
			(end 0.120396 0.3048)
			(stroke
				(width 0.1)
				(type default)
			)
			(layer "F.Fab")
		)
		(pad "1" smd circle
			(at -0.40005 0)
			(size 0 0)
			(layers "F.Cu" "F.Mask" "F.Paste")
			(net "P1V8_VDDA_PEX1")
		)
		(pad "2" smd circle
			(at 0.40005 0)
			(size 0 0)
			(layers "F.Cu" "F.Mask" "F.Paste")
			(net "P1V8_VDDA_PEX1_R")
		)
	)
	(footprint ""
		(layer "F.Cu")
		(at 328.699368 -112.903508 90)
		(property "Reference" "PC804"
			(at 0 0 90)
			(layer "F.SilkS")
			(hide yes)
			(effects
				(font
					(size 1.27 1.27)
				)
			)
		)
		(property "Value" ""
			(at 0 0 90)
			(layer "F.Fab")
			(effects
				(font
					(size 1.27 1.27)
				)
			)
		)
		(duplicate_pad_numbers_are_jumpers no)
		(fp_line
			(start 1.524 -0.762)
			(end 1.524 0.762)
			(stroke
				(width 0.1524)
				(type default)
			)
			(layer "F.SilkS")
		)
		(fp_line
			(start -1.524 -0.762)
			(end 1.524 -0.762)
			(stroke
				(width 0.1524)
				(type default)
			)
			(layer "F.SilkS")
		)
		(fp_line
			(start 1.524 0.762)
			(end -1.524 0.762)
			(stroke
				(width 0.1524)
				(type default)
			)
			(layer "F.SilkS")
		)
		(fp_line
			(start -1.524 0.762)
			(end -1.524 -0.762)
			(stroke
				(width 0.1524)
				(type default)
			)
			(layer "F.SilkS")
		)
		(fp_line
			(start 1.1049 -0.724916)
			(end -1.1049 -0.724916)
			(stroke
				(width 0.1)
				(type default)
			)
			(layer "F.Fab")
		)
		(fp_line
			(start -1.1049 -0.724916)
			(end -1.1049 0.724916)
			(stroke
				(width 0.1)
				(type default)
			)
			(layer "F.Fab")
		)
		(fp_line
			(start 1.1049 0.724916)
			(end 1.1049 -0.724916)
			(stroke
				(width 0.1)
				(type default)
			)
			(layer "F.Fab")
		)
		(fp_line
			(start -1.1049 0.724916)
			(end 1.1049 0.724916)
			(stroke
				(width 0.1)
				(type default)
			)
			(layer "F.Fab")
		)
		(pad "1" smd rect
			(at -0.889 0 270)
			(size 1.016 1.27)
			(layers "F.Cu" "F.Mask" "F.Paste")
			(net "P12V_NIC5_R")
		)
		(pad "2" smd rect
			(at 0.889 0 270)
			(size 1.016 1.27)
			(layers "F.Cu" "F.Mask" "F.Paste")
			(net "GND")
		)
	)
)
